(kicad_pcb
	(version 20260206)
	(generator "pcbnew")
	(generator_version "10.0")
	(general
		(thickness 1.6)
		(legacy_teardrops no)
	)
	(paper "A4")
	(title_block
		(title "01162023_DA0F0TEBIF0_F0T_Expander_BD_F_brd_V02_OCP.brd")
		(comment 1 "Grand Teton / footprints 3027-3034 of 9728")
	)
	(layers
		(0 "F.Cu" signal "TOP")
		(4 "In1.Cu" signal "GND")
		(6 "In2.Cu" signal "VCC")
		(8 "In3.Cu" signal "VCC1")
		(10 "In4.Cu" signal "GND1")
		(12 "In5.Cu" signal "IN1")
		(14 "In6.Cu" signal "GND2")
		(16 "In7.Cu" signal "IN2")
		(18 "In8.Cu" signal "GND3")
		(20 "In9.Cu" signal "IN3")
		(22 "In10.Cu" signal "GND4")
		(24 "In11.Cu" signal "IN4")
		(26 "In12.Cu" signal "GND5")
		(28 "In13.Cu" signal "IN5")
		(30 "In14.Cu" signal "GND6")
		(32 "In15.Cu" signal "IN6")
		(34 "In16.Cu" signal "GND7")
		(2 "B.Cu" signal "BOTTOM")
		(9 "F.Adhes" user "F.Adhesive")
		(11 "B.Adhes" user "B.Adhesive")
		(13 "F.Paste" user "Package Geometry/Pastemask Top")
		(15 "B.Paste" user "Package Geometry/Pastemask Bottom")
		(5 "F.SilkS" user "Ref Des/Silkscreen Top")
		(7 "B.SilkS" user "Ref Des/Silkscreen Bottom")
		(1 "F.Mask" user "Board Geometry/Soldermask Top")
		(3 "B.Mask" user "Board Geometry/Soldermask Bottom")
		(17 "Dwgs.User" user "User.Drawings")
		(19 "Cmts.User" user "User.Comments")
		(21 "Eco1.User" user "User.Eco1")
		(23 "Eco2.User" user "User.Eco2")
		(25 "Edge.Cuts" user "Board Geometry/Outline")
		(27 "Margin" user)
		(31 "F.CrtYd" user "Package Geometry/Place Bound Top")
		(29 "B.CrtYd" user "Package Geometry/Place Bound Bottom")
		(35 "F.Fab" user "Ref Des/Assembly Top")
		(33 "B.Fab" user "Ref Des/Assembly Bottom")
	)
	(footprint ""
		(layer "F.Cu")
		(at 198.913496 -113.41354 180)
		(property "Reference" "R185"
			(at 0 0 180)
			(layer "F.SilkS")
			(hide yes)
			(effects
				(font
					(size 1.27 1.27)
				)
			)
		)
		(property "Value" ""
			(at 0 0 180)
			(layer "F.Fab")
			(effects
				(font
					(size 1.27 1.27)
				)
			)
		)
		(duplicate_pad_numbers_are_jumpers no)
		(fp_line
			(start 0.7874 0.4064)
			(end -0.7874 0.4064)
			(stroke
				(width 0.1524)
				(type default)
			)
			(layer "F.SilkS")
		)
		(fp_line
			(start 0.7874 -0.4064)
			(end 0.7874 0.4064)
			(stroke
				(width 0.1524)
				(type default)
			)
			(layer "F.SilkS")
		)
		(fp_line
			(start -0.7874 0.4064)
			(end -0.7874 -0.4064)
			(stroke
				(width 0.1524)
				(type default)
			)
			(layer "F.SilkS")
		)
		(fp_line
			(start -0.7874 -0.4064)
			(end 0.7874 -0.4064)
			(stroke
				(width 0.1524)
				(type default)
			)
			(layer "F.SilkS")
		)
		(fp_line
			(start 0.67945 0.3048)
			(end 0.120396 0.3048)
			(stroke
				(width 0.1)
				(type default)
			)
			(layer "F.Fab")
		)
		(fp_line
			(start 0.67945 -0.3048)
			(end 0.67945 0.3048)
			(stroke
				(width 0.1)
				(type default)
			)
			(layer "F.Fab")
		)
		(fp_line
			(start 0.12065 -0.2794)
			(end 0.12065 -0.3048)
			(stroke
				(width 0.1)
				(type default)
			)
			(layer "F.Fab")
		)
		(fp_line
			(start 0.12065 -0.3048)
			(end 0.67945 -0.3048)
			(stroke
				(width 0.1)
				(type default)
			)
			(layer "F.Fab")
		)
		(fp_line
			(start 0.120396 0.3048)
			(end 0.120396 0.2794)
			(stroke
				(width 0.1)
				(type default)
			)
			(layer "F.Fab")
		)
		(fp_line
			(start 0.120396 0.2794)
			(end -0.12065 0.2794)
			(stroke
				(width 0.1)
				(type default)
			)
			(layer "F.Fab")
		)
		(fp_line
			(start -0.12065 0.3048)
			(end -0.67945 0.3048)
			(stroke
				(width 0.1)
				(type default)
			)
			(layer "F.Fab")
		)
		(fp_line
			(start -0.12065 0.2794)
			(end -0.12065 0.3048)
			(stroke
				(width 0.1)
				(type default)
			)
			(layer "F.Fab")
		)
		(fp_line
			(start -0.12065 -0.2794)
			(end 0.12065 -0.2794)
			(stroke
				(width 0.1)
				(type default)
			)
			(layer "F.Fab")
		)
		(fp_line
			(start -0.12065 -0.305054)
			(end -0.12065 -0.2794)
			(stroke
				(width 0.1)
				(type default)
			)
			(layer "F.Fab")
		)
		(fp_line
			(start -0.67945 0.3048)
			(end -0.67945 -0.305054)
			(stroke
				(width 0.1)
				(type default)
			)
			(layer "F.Fab")
		)
		(fp_line
			(start -0.67945 -0.305054)
			(end -0.12065 -0.305054)
			(stroke
				(width 0.1)
				(type default)
			)
			(layer "F.Fab")
		)
		(pad "1" smd circle
			(at -0.40005 0 180)
			(size 0 0)
			(layers "F.Cu" "F.Mask" "F.Paste")
			(net "NIC3_BIF1_N")
		)
		(pad "2" smd circle
			(at 0.40005 0 180)
			(size 0 0)
			(layers "F.Cu" "F.Mask" "F.Paste")
			(net "GND")
		)
	)
	(footprint ""
		(layer "F.Cu")
		(at 341.546942 -38.49116 180)
		(property "Reference" "R6112"
			(at 0 0 180)
			(layer "F.SilkS")
			(hide yes)
			(effects
				(font
					(size 1.27 1.27)
				)
			)
		)
		(property "Value" ""
			(at 0 0 180)
			(layer "F.Fab")
			(effects
				(font
					(size 1.27 1.27)
				)
			)
		)
		(duplicate_pad_numbers_are_jumpers no)
		(fp_line
			(start 0.7874 0.4064)
			(end -0.7874 0.4064)
			(stroke
				(width 0.1524)
				(type default)
			)
			(layer "F.SilkS")
		)
		(fp_line
			(start 0.7874 -0.4064)
			(end 0.7874 0.4064)
			(stroke
				(width 0.1524)
				(type default)
			)
			(layer "F.SilkS")
		)
		(fp_line
			(start -0.7874 0.4064)
			(end -0.7874 -0.4064)
			(stroke
				(width 0.1524)
				(type default)
			)
			(layer "F.SilkS")
		)
		(fp_line
			(start -0.7874 -0.4064)
			(end 0.7874 -0.4064)
			(stroke
				(width 0.1524)
				(type default)
			)
			(layer "F.SilkS")
		)
		(fp_line
			(start 0.67945 0.3048)
			(end 0.120396 0.3048)
			(stroke
				(width 0.1)
				(type default)
			)
			(layer "F.Fab")
		)
		(fp_line
			(start 0.67945 -0.3048)
			(end 0.67945 0.3048)
			(stroke
				(width 0.1)
				(type default)
			)
			(layer "F.Fab")
		)
		(fp_line
			(start 0.12065 -0.2794)
			(end 0.12065 -0.3048)
			(stroke
				(width 0.1)
				(type default)
			)
			(layer "F.Fab")
		)
		(fp_line
			(start 0.12065 -0.3048)
			(end 0.67945 -0.3048)
			(stroke
				(width 0.1)
				(type default)
			)
			(layer "F.Fab")
		)
		(fp_line
			(start 0.120396 0.3048)
			(end 0.120396 0.2794)
			(stroke
				(width 0.1)
				(type default)
			)
			(layer "F.Fab")
		)
		(fp_line
			(start 0.120396 0.2794)
			(end -0.12065 0.2794)
			(stroke
				(width 0.1)
				(type default)
			)
			(layer "F.Fab")
		)
		(fp_line
			(start -0.12065 0.3048)
			(end -0.67945 0.3048)
			(stroke
				(width 0.1)
				(type default)
			)
			(layer "F.Fab")
		)
		(fp_line
			(start -0.12065 0.2794)
			(end -0.12065 0.3048)
			(stroke
				(width 0.1)
				(type default)
			)
			(layer "F.Fab")
		)
		(fp_line
			(start -0.12065 -0.2794)
			(end 0.12065 -0.2794)
			(stroke
				(width 0.1)
				(type default)
			)
			(layer "F.Fab")
		)
		(fp_line
			(start -0.12065 -0.305054)
			(end -0.12065 -0.2794)
			(stroke
				(width 0.1)
				(type default)
			)
			(layer "F.Fab")
		)
		(fp_line
			(start -0.67945 0.3048)
			(end -0.67945 -0.305054)
			(stroke
				(width 0.1)
				(type default)
			)
			(layer "F.Fab")
		)
		(fp_line
			(start -0.67945 -0.305054)
			(end -0.12065 -0.305054)
			(stroke
				(width 0.1)
				(type default)
			)
			(layer "F.Fab")
		)
		(pad "1" smd circle
			(at -0.40005 0 180)
			(size 0 0)
			(layers "F.Cu" "F.Mask" "F.Paste")
			(net "P3V3_SSD12_PG_G1")
		)
		(pad "2" smd circle
			(at 0.40005 0 180)
			(size 0 0)
			(layers "F.Cu" "F.Mask" "F.Paste")
			(net "GND")
		)
	)
	(footprint ""
		(layer "F.Cu")
		(at 234.695238 -35.48253)
		(property "Reference" "U391"
			(at -2.588768 1.34493 90)
			(unlocked yes)
			(layer "F.SilkS")
			(effects
				(font
					(size 0.7874 0.5842)
					(thickness 0.1524)
				)
				(justify left)
			)
		)
		(property "Value" ""
			(at 0 0 0)
			(layer "F.Fab")
			(effects
				(font
					(size 1.27 1.27)
				)
			)
		)
		(duplicate_pad_numbers_are_jumpers no)
		(fp_line
			(start -1.3462 -1.1938)
			(end -1.3462 1.1684)
			(stroke
				(width 0.1524)
				(type default)
			)
			(layer "F.SilkS")
		)
		(fp_line
			(start -1.3462 1.1938)
			(end 1.3462 1.1938)
			(stroke
				(width 0.1524)
				(type default)
			)
			(layer "F.SilkS")
		)
		(fp_line
			(start 1.3462 -1.1938)
			(end -1.3462 -1.1938)
			(stroke
				(width 0.1524)
				(type default)
			)
			(layer "F.SilkS")
		)
		(fp_line
			(start 1.3462 1.1938)
			(end 1.3462 -1.1938)
			(stroke
				(width 0.1524)
				(type default)
			)
			(layer "F.SilkS")
		)
		(fp_poly
			(pts
				(xy -1.447038 -0.760476) (xy -2.052066 -0.457962) (xy -2.052066 -1.06299)
			)
			(stroke
				(width 0)
				(type default)
			)
			(fill yes)
			(layer "F.SilkS")
		)
		(fp_line
			(start -0.674878 -1.124966)
			(end -0.674878 1.124966)
			(stroke
				(width 0.1)
				(type default)
			)
			(layer "F.Fab")
		)
		(fp_line
			(start -0.674878 1.124966)
			(end 0.674878 1.124966)
			(stroke
				(width 0.1)
				(type default)
			)
			(layer "F.Fab")
		)
		(fp_line
			(start 0.674878 -1.124966)
			(end -0.674878 -1.124966)
			(stroke
				(width 0.1)
				(type default)
			)
			(layer "F.Fab")
		)
		(fp_line
			(start 0.674878 1.124966)
			(end 0.674878 -1.124966)
			(stroke
				(width 0.1)
				(type default)
			)
			(layer "F.Fab")
		)
		(fp_poly
			(pts
				(xy -1.447038 -0.760476) (xy -2.052066 -0.457962) (xy -2.052066 -1.06299)
			)
			(stroke
				(width 0)
				(type default)
			)
			(fill yes)
			(layer "F.Fab")
		)
		(pad "1" smd rect
			(at -0.899922 -0.750062)
			(size 0.6096 0.6096)
			(layers "F.Cu" "F.Mask" "F.Paste")
			(net "PWRGD_P3V3_SSD8_R")
		)
		(pad "2" smd rect
			(at -0.899922 0 90)
			(size 0.4064 0.6096)
			(layers "F.Cu" "F.Mask" "F.Paste")
			(net "RST_SMB_SSD8_N")
		)
		(pad "3" smd rect
			(at -0.899922 0.750062)
			(size 0.6096 0.6096)
			(layers "F.Cu" "F.Mask" "F.Paste")
			(net "GND")
		)
		(pad "4" smd rect
			(at 0.899922 0.750062)
			(size 0.6096 0.6096)
			(layers "F.Cu" "F.Mask" "F.Paste")
			(net "RST_SMB_SSD8_ISO_N")
		)
		(pad "5" smd rect
			(at 0.899922 -0.750062)
			(size 0.6096 0.6096)
			(layers "F.Cu" "F.Mask" "F.Paste")
			(net "P3V3_AUX")
		)
	)
	(footprint ""
		(layer "F.Cu")
		(at 340.641432 -303.649634 90)
		(property "Reference" "PC164"
			(at 0 0 90)
			(layer "F.SilkS")
			(hide yes)
			(effects
				(font
					(size 1.27 1.27)
				)
			)
		)
		(property "Value" ""
			(at 0 0 90)
			(layer "F.Fab")
			(effects
				(font
					(size 1.27 1.27)
				)
			)
		)
		(duplicate_pad_numbers_are_jumpers no)
		(fp_line
			(start 1.524 -0.762)
			(end 1.524 0.762)
			(stroke
				(width 0.1524)
				(type default)
			)
			(layer "F.SilkS")
		)
		(fp_line
			(start -1.524 -0.762)
			(end 1.524 -0.762)
			(stroke
				(width 0.1524)
				(type default)
			)
			(layer "F.SilkS")
		)
		(fp_line
			(start 1.524 0.762)
			(end -1.524 0.762)
			(stroke
				(width 0.1524)
				(type default)
			)
			(layer "F.SilkS")
		)
		(fp_line
			(start -1.524 0.762)
			(end -1.524 -0.762)
			(stroke
				(width 0.1524)
				(type default)
			)
			(layer "F.SilkS")
		)
		(fp_line
			(start 1.1049 -0.724916)
			(end -1.1049 -0.724916)
			(stroke
				(width 0.1)
				(type default)
			)
			(layer "F.Fab")
		)
		(fp_line
			(start -1.1049 -0.724916)
			(end -1.1049 0.724916)
			(stroke
				(width 0.1)
				(type default)
			)
			(layer "F.Fab")
		)
		(fp_line
			(start 1.1049 0.724916)
			(end 1.1049 -0.724916)
			(stroke
				(width 0.1)
				(type default)
			)
			(layer "F.Fab")
		)
		(fp_line
			(start -1.1049 0.724916)
			(end 1.1049 0.724916)
			(stroke
				(width 0.1)
				(type default)
			)
			(layer "F.Fab")
		)
		(pad "1" smd rect
			(at -0.889 0 270)
			(size 1.016 1.27)
			(layers "F.Cu" "F.Mask" "F.Paste")
			(net "P0V8_PEX2")
		)
		(pad "2" smd rect
			(at 0.889 0 270)
			(size 1.016 1.27)
			(layers "F.Cu" "F.Mask" "F.Paste")
			(net "GND")
		)
	)
	(footprint ""
		(layer "F.Cu")
		(at 213.17966 -179.843176 -90)
		(property "Reference" "R5420"
			(at 0 0 270)
			(layer "F.SilkS")
			(hide yes)
			(effects
				(font
					(size 1.27 1.27)
				)
			)
		)
		(property "Value" ""
			(at 0 0 270)
			(layer "F.Fab")
			(effects
				(font
					(size 1.27 1.27)
				)
			)
		)
		(duplicate_pad_numbers_are_jumpers no)
		(fp_line
			(start -0.7874 0.4064)
			(end -0.7874 -0.4064)
			(stroke
				(width 0.1524)
				(type default)
			)
			(layer "F.SilkS")
		)
		(fp_line
			(start 0.7874 0.4064)
			(end -0.7874 0.4064)
			(stroke
				(width 0.1524)
				(type default)
			)
			(layer "F.SilkS")
		)
		(fp_line
			(start -0.7874 -0.4064)
			(end 0.7874 -0.4064)
			(stroke
				(width 0.1524)
				(type default)
			)
			(layer "F.SilkS")
		)
		(fp_line
			(start 0.7874 -0.4064)
			(end 0.7874 0.4064)
			(stroke
				(width 0.1524)
				(type default)
			)
			(layer "F.SilkS")
		)
		(fp_line
			(start -0.67945 0.3048)
			(end -0.67945 -0.305054)
			(stroke
				(width 0.1)
				(type default)
			)
			(layer "F.Fab")
		)
		(fp_line
			(start -0.12065 0.3048)
			(end -0.67945 0.3048)
			(stroke
				(width 0.1)
				(type default)
			)
			(layer "F.Fab")
		)
		(fp_line
			(start 0.120396 0.3048)
			(end 0.120396 0.2794)
			(stroke
				(width 0.1)
				(type default)
			)
			(layer "F.Fab")
		)
		(fp_line
			(start 0.67945 0.3048)
			(end 0.120396 0.3048)
			(stroke
				(width 0.1)
				(type default)
			)
			(layer "F.Fab")
		)
		(fp_line
			(start -0.12065 0.2794)
			(end -0.12065 0.3048)
			(stroke
				(width 0.1)
				(type default)
			)
			(layer "F.Fab")
		)
		(fp_line
			(start 0.120396 0.2794)
			(end -0.12065 0.2794)
			(stroke
				(width 0.1)
				(type default)
			)
			(layer "F.Fab")
		)
		(fp_line
			(start -0.12065 -0.2794)
			(end 0.12065 -0.2794)
			(stroke
				(width 0.1)
				(type default)
			)
			(layer "F.Fab")
		)
		(fp_line
			(start 0.12065 -0.2794)
			(end 0.12065 -0.3048)
			(stroke
				(width 0.1)
				(type default)
			)
			(layer "F.Fab")
		)
		(fp_line
			(start 0.12065 -0.3048)
			(end 0.67945 -0.3048)
			(stroke
				(width 0.1)
				(type default)
			)
			(layer "F.Fab")
		)
		(fp_line
			(start 0.67945 -0.3048)
			(end 0.67945 0.3048)
			(stroke
				(width 0.1)
				(type default)
			)
			(layer "F.Fab")
		)
		(fp_line
			(start -0.67945 -0.305054)
			(end -0.12065 -0.305054)
			(stroke
				(width 0.1)
				(type default)
			)
			(layer "F.Fab")
		)
		(fp_line
			(start -0.12065 -0.305054)
			(end -0.12065 -0.2794)
			(stroke
				(width 0.1)
				(type default)
			)
			(layer "F.Fab")
		)
		(pad "1" smd circle
			(at -0.40005 0 270)
			(size 0 0)
			(layers "F.Cu" "F.Mask" "F.Paste")
			(net "SEL_FLASH_PEX2_BUF_R")
		)
		(pad "2" smd circle
			(at 0.40005 0 270)
			(size 0 0)
			(layers "F.Cu" "F.Mask" "F.Paste")
			(net "P3V3_AUX")
		)
	)
	(footprint ""
		(layer "F.Cu")
		(at 407.295096 -103.814372 180)
		(property "Reference" "R375"
			(at 0 0 180)
			(layer "F.SilkS")
			(hide yes)
			(effects
				(font
					(size 1.27 1.27)
				)
			)
		)
		(property "Value" ""
			(at 0 0 180)
			(layer "F.Fab")
			(effects
				(font
					(size 1.27 1.27)
				)
			)
		)
		(duplicate_pad_numbers_are_jumpers no)
		(fp_line
			(start 0.7874 0.4064)
			(end -0.7874 0.4064)
			(stroke
				(width 0.1524)
				(type default)
			)
			(layer "F.SilkS")
		)
		(fp_line
			(start 0.7874 -0.4064)
			(end 0.7874 0.4064)
			(stroke
				(width 0.1524)
				(type default)
			)
			(layer "F.SilkS")
		)
		(fp_line
			(start -0.7874 0.4064)
			(end -0.7874 -0.4064)
			(stroke
				(width 0.1524)
				(type default)
			)
			(layer "F.SilkS")
		)
		(fp_line
			(start -0.7874 -0.4064)
			(end 0.7874 -0.4064)
			(stroke
				(width 0.1524)
				(type default)
			)
			(layer "F.SilkS")
		)
		(fp_line
			(start 0.67945 0.3048)
			(end 0.120396 0.3048)
			(stroke
				(width 0.1)
				(type default)
			)
			(layer "F.Fab")
		)
		(fp_line
			(start 0.67945 -0.3048)
			(end 0.67945 0.3048)
			(stroke
				(width 0.1)
				(type default)
			)
			(layer "F.Fab")
		)
		(fp_line
			(start 0.12065 -0.2794)
			(end 0.12065 -0.3048)
			(stroke
				(width 0.1)
				(type default)
			)
			(layer "F.Fab")
		)
		(fp_line
			(start 0.12065 -0.3048)
			(end 0.67945 -0.3048)
			(stroke
				(width 0.1)
				(type default)
			)
			(layer "F.Fab")
		)
		(fp_line
			(start 0.120396 0.3048)
			(end 0.120396 0.2794)
			(stroke
				(width 0.1)
				(type default)
			)
			(layer "F.Fab")
		)
		(fp_line
			(start 0.120396 0.2794)
			(end -0.12065 0.2794)
			(stroke
				(width 0.1)
				(type default)
			)
			(layer "F.Fab")
		)
		(fp_line
			(start -0.12065 0.3048)
			(end -0.67945 0.3048)
			(stroke
				(width 0.1)
				(type default)
			)
			(layer "F.Fab")
		)
		(fp_line
			(start -0.12065 0.2794)
			(end -0.12065 0.3048)
			(stroke
				(width 0.1)
				(type default)
			)
			(layer "F.Fab")
		)
		(fp_line
			(start -0.12065 -0.2794)
			(end 0.12065 -0.2794)
			(stroke
				(width 0.1)
				(type default)
			)
			(layer "F.Fab")
		)
		(fp_line
			(start -0.12065 -0.305054)
			(end -0.12065 -0.2794)
			(stroke
				(width 0.1)
				(type default)
			)
			(layer "F.Fab")
		)
		(fp_line
			(start -0.67945 0.3048)
			(end -0.67945 -0.305054)
			(stroke
				(width 0.1)
				(type default)
			)
			(layer "F.Fab")
		)
		(fp_line
			(start -0.67945 -0.305054)
			(end -0.12065 -0.305054)
			(stroke
				(width 0.1)
				(type default)
			)
			(layer "F.Fab")
		)
		(pad "1" smd circle
			(at -0.40005 0 180)
			(size 0 0)
			(layers "F.Cu" "F.Mask" "F.Paste")
			(net "NCSI_NIC7_TXD0")
		)
		(pad "2" smd circle
			(at 0.40005 0 180)
			(size 0 0)
			(layers "F.Cu" "F.Mask" "F.Paste")
			(net "GND")
		)
	)
	(footprint ""
		(layer "F.Cu")
		(at 67.564762 -350.098614 90)
		(property "Reference" "C121"
			(at 0 0 90)
			(layer "F.SilkS")
			(hide yes)
			(effects
				(font
					(size 1.27 1.27)
				)
			)
		)
		(property "Value" ""
			(at 0 0 90)
			(layer "F.Fab")
			(effects
				(font
					(size 1.27 1.27)
				)
			)
		)
		(duplicate_pad_numbers_are_jumpers no)
		(fp_line
			(start 0.299974 -0.150114)
			(end 0.299974 0.150114)
			(stroke
				(width 0.1)
				(type default)
			)
			(layer "F.Fab")
		)
		(fp_line
			(start -0.299974 -0.150114)
			(end 0.299974 -0.150114)
			(stroke
				(width 0.1)
				(type default)
			)
			(layer "F.Fab")
		)
		(fp_line
			(start 0.299974 0.150114)
			(end -0.299974 0.150114)
			(stroke
				(width 0.1)
				(type default)
			)
			(layer "F.Fab")
		)
		(fp_line
			(start -0.299974 0.150114)
			(end -0.299974 -0.150114)
			(stroke
				(width 0.1)
				(type default)
			)
			(layer "F.Fab")
		)
		(pad "1" smd rect
			(at -0.2667 0 90)
			(size 0.3048 0.381)
			(layers "F.Cu" "F.Mask" "F.Paste")
			(net "P5E_PEX0_STN5_TX_DP<83>")
		)
		(pad "2" smd rect
			(at 0.2667 0 90)
			(size 0.3048 0.381)
			(layers "F.Cu" "F.Mask" "F.Paste")
			(net "P5E_PEX0_STN5_TX_C_DP<83>")
		)
	)
	(footprint ""
		(layer "F.Cu")
		(at 325.827644 -356.244906 90)
		(property "Reference" "C564"
			(at 0 0 90)
			(layer "F.SilkS")
			(hide yes)
			(effects
				(font
					(size 1.27 1.27)
				)
			)
		)
		(property "Value" ""
			(at 0 0 90)
			(layer "F.Fab")
			(effects
				(font
					(size 1.27 1.27)
				)
			)
		)
		(duplicate_pad_numbers_are_jumpers no)
		(fp_line
			(start 0.299974 -0.150114)
			(end 0.299974 0.150114)
			(stroke
				(width 0.1)
				(type default)
			)
			(layer "F.Fab")
		)
		(fp_line
			(start -0.299974 -0.150114)
			(end 0.299974 -0.150114)
			(stroke
				(width 0.1)
				(type default)
			)
			(layer "F.Fab")
		)
		(fp_line
			(start 0.299974 0.150114)
			(end -0.299974 0.150114)
			(stroke
				(width 0.1)
				(type default)
			)
			(layer "F.Fab")
		)
		(fp_line
			(start -0.299974 0.150114)
			(end -0.299974 -0.150114)
			(stroke
				(width 0.1)
				(type default)
			)
			(layer "F.Fab")
		)
		(pad "1" smd rect
			(at -0.2667 0 90)
			(size 0.3048 0.381)
			(layers "F.Cu" "F.Mask" "F.Paste")
			(net "P5E_PEX2_STN6_TX_DN<105>")
		)
		(pad "2" smd rect
			(at 0.2667 0 90)
			(size 0.3048 0.381)
			(layers "F.Cu" "F.Mask" "F.Paste")
			(net "P5E_PEX2_STN6_TX_C_DN<105>")
		)
	)
)
